# T6G (Grand Teton) — schematic netlist excerpt (pin names and nets, part order shuffled) for the footprints in the layout excerpt that follows; sources: Cadence DE-HDL packaged netlist, KiCad conversion of 04192023_DAF0TMB3IC0_F0TG_MB_C_brd_V02_OCP.brd

C2182  Q_CAP  22UF 4V 20% X6S  pkg C0402  page 69 : A = PVDDCR_CPU0_P0 ; B = GND
PC411_4  Q_CAP  22UF 16V 20% X6S  pkg C0805  page 219 : A = SW_P12V_AUX_PVDDCR_CPU1_P1_FLT ; B = GND
C2227  Q_CAP  22UF 4V 20% X6S  pkg C0402  page 69 : A = PVDDCR_CPU1_P0 ; B = GND

(kicad_pcb
	(version 20260206)
	(generator "pcbnew")
	(generator_version "10.0")
	(general
		(thickness 1.6)
		(legacy_teardrops no)
	)
	(paper "A4")
	(title_block
		(title "04192023_DAF0TMB3IC0_F0TG_MB_C_brd_V02_OCP.brd")
		(comment 1 "Grand Teton / footprints 7892-7894 of 8354")
	)
	(layers
		(0 "F.Cu" signal "TOP")
		(4 "In1.Cu" signal "GND")
		(6 "In2.Cu" signal "IN1")
		(8 "In3.Cu" signal "GND1")
		(10 "In4.Cu" signal "IN2")
		(12 "In5.Cu" signal "GND2")
		(14 "In6.Cu" signal "IN3")
		(16 "In7.Cu" signal "GND3")
		(18 "In8.Cu" signal "VCC")
		(20 "In9.Cu" signal "VCC1")
		(22 "In10.Cu" signal "GND4")
		(24 "In11.Cu" signal "IN4")
		(26 "In12.Cu" signal "GND5")
		(28 "In13.Cu" signal "IN5")
		(30 "In14.Cu" signal "GND6")
		(32 "In15.Cu" signal "IN6")
		(34 "In16.Cu" signal "GND7")
		(2 "B.Cu" signal "BOTTOM")
		(9 "F.Adhes" user "F.Adhesive")
		(11 "B.Adhes" user "B.Adhesive")
		(13 "F.Paste" user "Package Geometry/Pastemask Top")
		(15 "B.Paste" user "Package Geometry/Pastemask Bottom")
		(5 "F.SilkS" user "Ref Des/Silkscreen Top")
		(7 "B.SilkS" user "Ref Des/Silkscreen Bottom")
		(1 "F.Mask" user "Board Geometry/Soldermask Top")
		(3 "B.Mask" user "Board Geometry/Soldermask Bottom")
		(17 "Dwgs.User" user "User.Drawings")
		(19 "Cmts.User" user "User.Comments")
		(21 "Eco1.User" user "User.Eco1")
		(23 "Eco2.User" user "User.Eco2")
		(25 "Edge.Cuts" user "Board Geometry/Outline")
		(27 "Margin" user)
		(31 "F.CrtYd" user "Package Geometry/Place Bound Top")
		(29 "B.CrtYd" user "Package Geometry/Place Bound Bottom")
		(35 "F.Fab" user "Ref Des/Assembly Top")
		(33 "B.Fab" user "Ref Des/Assembly Bottom")
	)
	(footprint ""
		(layer "B.Cu")
		(at 356.311454 -267.52931)
		(property "Reference" "C2227"
			(at 0 0 0)
			(layer "B.SilkS")
			(hide yes)
			(effects
				(font
					(size 1.27 1.27)
				)
				(justify mirror)
			)
		)
		(property "Value" ""
			(at 0 0 0)
			(layer "B.Fab")
			(effects
				(font
					(size 1.27 1.27)
				)
				(justify mirror)
			)
		)
		(duplicate_pad_numbers_are_jumpers no)
		(fp_line
			(start -0.7874 -0.4064)
			(end -0.7874 0.4064)
			(stroke
				(width 0.1524)
				(type default)
			)
			(layer "B.SilkS")
		)
		(fp_line
			(start -0.7874 0.4064)
			(end 0.7874 0.4064)
			(stroke
				(width 0.1524)
				(type default)
			)
			(layer "B.SilkS")
		)
		(fp_line
			(start 0.7874 -0.4064)
			(end -0.7874 -0.4064)
			(stroke
				(width 0.1524)
				(type default)
			)
			(layer "B.SilkS")
		)
		(fp_line
			(start 0.7874 0.4064)
			(end 0.7874 -0.4064)
			(stroke
				(width 0.1524)
				(type default)
			)
			(layer "B.SilkS")
		)
		(fp_line
			(start -0.67945 -0.3048)
			(end -0.67945 0.3048)
			(stroke
				(width 0.1)
				(type default)
			)
			(layer "B.Fab")
		)
		(fp_line
			(start -0.67945 0.3048)
			(end -0.120396 0.3048)
			(stroke
				(width 0.1)
				(type default)
			)
			(layer "B.Fab")
		)
		(fp_line
			(start -0.12065 -0.3048)
			(end -0.67945 -0.3048)
			(stroke
				(width 0.1)
				(type default)
			)
			(layer "B.Fab")
		)
		(fp_line
			(start -0.12065 -0.2794)
			(end -0.12065 -0.3048)
			(stroke
				(width 0.1)
				(type default)
			)
			(layer "B.Fab")
		)
		(fp_line
			(start -0.120396 0.2794)
			(end 0.12065 0.2794)
			(stroke
				(width 0.1)
				(type default)
			)
			(layer "B.Fab")
		)
		(fp_line
			(start -0.120396 0.3048)
			(end -0.120396 0.2794)
			(stroke
				(width 0.1)
				(type default)
			)
			(layer "B.Fab")
		)
		(fp_line
			(start 0.12065 -0.305054)
			(end 0.12065 -0.2794)
			(stroke
				(width 0.1)
				(type default)
			)
			(layer "B.Fab")
		)
		(fp_line
			(start 0.12065 -0.2794)
			(end -0.12065 -0.2794)
			(stroke
				(width 0.1)
				(type default)
			)
			(layer "B.Fab")
		)
		(fp_line
			(start 0.12065 0.2794)
			(end 0.12065 0.3048)
			(stroke
				(width 0.1)
				(type default)
			)
			(layer "B.Fab")
		)
		(fp_line
			(start 0.12065 0.3048)
			(end 0.67945 0.3048)
			(stroke
				(width 0.1)
				(type default)
			)
			(layer "B.Fab")
		)
		(fp_line
			(start 0.67945 -0.305054)
			(end 0.12065 -0.305054)
			(stroke
				(width 0.1)
				(type default)
			)
			(layer "B.Fab")
		)
		(fp_line
			(start 0.67945 0.3048)
			(end 0.67945 -0.305054)
			(stroke
				(width 0.1)
				(type default)
			)
			(layer "B.Fab")
		)
		(pad "1" smd circle
			(at 0.40005 0 180)
			(size 0 0)
			(layers "B.Cu" "B.Mask" "B.Paste")
			(net "PVDDCR_CPU1_P0")
		)
		(pad "2" smd circle
			(at -0.40005 0 180)
			(size 0 0)
			(layers "B.Cu" "B.Mask" "B.Paste")
			(net "GND")
		)
	)
	(footprint ""
		(layer "B.Cu")
		(at 358.057958 -248.916952 120)
		(property "Reference" "C2182"
			(at 0 0 120)
			(layer "B.SilkS")
			(hide yes)
			(effects
				(font
					(size 1.27 1.27)
				)
				(justify mirror)
			)
		)
		(property "Value" ""
			(at 0 0 120)
			(layer "B.Fab")
			(effects
				(font
					(size 1.27 1.27)
				)
				(justify mirror)
			)
		)
		(duplicate_pad_numbers_are_jumpers no)
		(fp_line
			(start 0.787516 -0.406438)
			(end -0.787425 -0.40652)
			(stroke
				(width 0.1524)
				(type default)
			)
			(layer "B.SilkS")
		)
		(fp_line
			(start 0.787425 0.40652)
			(end 0.787516 -0.406438)
			(stroke
				(width 0.1524)
				(type default)
			)
			(layer "B.SilkS")
		)
		(fp_line
			(start -0.787425 -0.40652)
			(end -0.787516 0.406438)
			(stroke
				(width 0.1524)
				(type default)
			)
			(layer "B.SilkS")
		)
		(fp_line
			(start -0.787516 0.406438)
			(end 0.787425 0.40652)
			(stroke
				(width 0.1524)
				(type default)
			)
			(layer "B.SilkS")
		)
		(fp_line
			(start 0.679475 -0.305158)
			(end 0.120732 -0.305125)
			(stroke
				(width 0.1)
				(type default)
			)
			(layer "B.Fab")
		)
		(fp_line
			(start 0.120732 -0.305125)
			(end 0.120554 -0.279418)
			(stroke
				(width 0.1)
				(type default)
			)
			(layer "B.Fab")
		)
		(fp_line
			(start 0.120554 -0.279418)
			(end -0.120587 -0.279326)
			(stroke
				(width 0.1)
				(type default)
			)
			(layer "B.Fab")
		)
		(fp_line
			(start -0.120536 -0.304813)
			(end -0.6795 -0.304908)
			(stroke
				(width 0.1)
				(type default)
			)
			(layer "B.Fab")
		)
		(fp_line
			(start -0.120587 -0.279326)
			(end -0.120536 -0.304813)
			(stroke
				(width 0.1)
				(type default)
			)
			(layer "B.Fab")
		)
		(fp_line
			(start 0.6795 0.304908)
			(end 0.679475 -0.305158)
			(stroke
				(width 0.1)
				(type default)
			)
			(layer "B.Fab")
		)
		(fp_line
			(start -0.6795 -0.304908)
			(end -0.679568 0.304811)
			(stroke
				(width 0.1)
				(type default)
			)
			(layer "B.Fab")
		)
		(fp_line
			(start 0.120587 0.279326)
			(end 0.120536 0.304813)
			(stroke
				(width 0.1)
				(type default)
			)
			(layer "B.Fab")
		)
		(fp_line
			(start 0.120536 0.304813)
			(end 0.6795 0.304908)
			(stroke
				(width 0.1)
				(type default)
			)
			(layer "B.Fab")
		)
		(fp_line
			(start -0.120334 0.279545)
			(end 0.120587 0.279326)
			(stroke
				(width 0.1)
				(type default)
			)
			(layer "B.Fab")
		)
		(fp_line
			(start -0.120258 0.304812)
			(end -0.120334 0.279545)
			(stroke
				(width 0.1)
				(type default)
			)
			(layer "B.Fab")
		)
		(fp_line
			(start -0.679568 0.304811)
			(end -0.120258 0.304812)
			(stroke
				(width 0.1)
				(type default)
			)
			(layer "B.Fab")
		)
		(pad "1" smd circle
			(at 0.40005 0 300)
			(size 0 0)
			(layers "B.Cu" "B.Mask" "B.Paste")
			(net "PVDDCR_CPU0_P0")
		)
		(pad "2" smd circle
			(at -0.40005 0 300)
			(size 0 0)
			(layers "B.Cu" "B.Mask" "B.Paste")
			(net "GND")
		)
	)
	(footprint ""
		(layer "B.Cu")
		(at 65.12433 -346.788994 90)
		(property "Reference" "PC411_4"
			(at 0 0 90)
			(layer "B.SilkS")
			(hide yes)
			(effects
				(font
					(size 1.27 1.27)
				)
				(justify mirror)
			)
		)
		(property "Value" ""
			(at 0 0 90)
			(layer "B.Fab")
			(effects
				(font
					(size 1.27 1.27)
				)
				(justify mirror)
			)
		)
		(duplicate_pad_numbers_are_jumpers no)
		(fp_line
			(start 1.524 -0.762)
			(end -1.524 -0.762)
			(stroke
				(width 0.1524)
				(type default)
			)
			(layer "B.SilkS")
		)
		(fp_line
			(start -1.524 -0.762)
			(end -1.524 0.762)
			(stroke
				(width 0.1524)
				(type default)
			)
			(layer "B.SilkS")
		)
		(fp_line
			(start 1.524 0.762)
			(end 1.524 -0.762)
			(stroke
				(width 0.1524)
				(type default)
			)
			(layer "B.SilkS")
		)
		(fp_line
			(start -1.524 0.762)
			(end 1.524 0.762)
			(stroke
				(width 0.1524)
				(type default)
			)
			(layer "B.SilkS")
		)
		(fp_line
			(start 1.1049 -0.724916)
			(end 1.1049 0.724916)
			(stroke
				(width 0.1)
				(type default)
			)
			(layer "B.Fab")
		)
		(fp_line
			(start -1.1049 -0.724916)
			(end 1.1049 -0.724916)
			(stroke
				(width 0.1)
				(type default)
			)
			(layer "B.Fab")
		)
		(fp_line
			(start 1.1049 0.724916)
			(end -1.1049 0.724916)
			(stroke
				(width 0.1)
				(type default)
			)
			(layer "B.Fab")
		)
		(fp_line
			(start -1.1049 0.724916)
			(end -1.1049 -0.724916)
			(stroke
				(width 0.1)
				(type default)
			)
			(layer "B.Fab")
		)
		(pad "1" smd rect
			(at 0.889 0 90)
			(size 1.016 1.27)
			(layers "B.Cu" "B.Mask" "B.Paste")
			(net "SW_P12V_AUX_PVDDCR_CPU1_P1_FLT")
		)
		(pad "2" smd rect
			(at -0.889 0 90)
			(size 1.016 1.27)
			(layers "B.Cu" "B.Mask" "B.Paste")
			(net "GND")
		)
	)
)
